# T6G (Grand Teton) — schematic netlist excerpt (pin names and nets, part order shuffled) for the footprints in the layout excerpt that follows; sources: Cadence DE-HDL packaged netlist, KiCad conversion of 04192023_DAF0TMB3IC0_F0TG_MB_C_brd_V02_OCP.brd

R775  Q_RES  23.2K 1% CHIP  pkg 0402LF  page 106 : A = PD_CHI_CPU1_DIMM_SAA ; B = GND
C792  Q_CAP  1UF 4V 20% X6S  pkg 0201  page 301 : A = P0V9_CPU0_RT2_2A ; B = GND
C6548  Q_CAP_DIFFBUS  DIFF BUS_0.22UF 6.3V 20% X6S  pkg C0201  page 286 : \1\ = P5E_CPU0_P1_TX_BUF_C_DN<7> ; \2\ = P5E_CPU0_P1_TX_BUF_DN<7>

(kicad_pcb
	(version 20260206)
	(generator "pcbnew")
	(generator_version "10.0")
	(general
		(thickness 1.6)
		(legacy_teardrops no)
	)
	(paper "A4")
	(title_block
		(title "04192023_DAF0TMB3IC0_F0TG_MB_C_brd_V02_OCP.brd")
		(comment 1 "Grand Teton / footprints 7831-7833 of 8354")
	)
	(layers
		(0 "F.Cu" signal "TOP")
		(4 "In1.Cu" signal "GND")
		(6 "In2.Cu" signal "IN1")
		(8 "In3.Cu" signal "GND1")
		(10 "In4.Cu" signal "IN2")
		(12 "In5.Cu" signal "GND2")
		(14 "In6.Cu" signal "IN3")
		(16 "In7.Cu" signal "GND3")
		(18 "In8.Cu" signal "VCC")
		(20 "In9.Cu" signal "VCC1")
		(22 "In10.Cu" signal "GND4")
		(24 "In11.Cu" signal "IN4")
		(26 "In12.Cu" signal "GND5")
		(28 "In13.Cu" signal "IN5")
		(30 "In14.Cu" signal "GND6")
		(32 "In15.Cu" signal "IN6")
		(34 "In16.Cu" signal "GND7")
		(2 "B.Cu" signal "BOTTOM")
		(9 "F.Adhes" user "F.Adhesive")
		(11 "B.Adhes" user "B.Adhesive")
		(13 "F.Paste" user "Package Geometry/Pastemask Top")
		(15 "B.Paste" user "Package Geometry/Pastemask Bottom")
		(5 "F.SilkS" user "Ref Des/Silkscreen Top")
		(7 "B.SilkS" user "Ref Des/Silkscreen Bottom")
		(1 "F.Mask" user "Board Geometry/Soldermask Top")
		(3 "B.Mask" user "Board Geometry/Soldermask Bottom")
		(17 "Dwgs.User" user "User.Drawings")
		(19 "Cmts.User" user "User.Comments")
		(21 "Eco1.User" user "User.Eco1")
		(23 "Eco2.User" user "User.Eco2")
		(25 "Edge.Cuts" user "Board Geometry/Outline")
		(27 "Margin" user)
		(31 "F.CrtYd" user "Package Geometry/Place Bound Top")
		(29 "B.CrtYd" user "Package Geometry/Place Bound Bottom")
		(35 "F.Fab" user "Ref Des/Assembly Top")
		(33 "B.Fab" user "Ref Des/Assembly Bottom")
	)
	(footprint ""
		(layer "B.Cu")
		(at 326.742806 -416.899344 90)
		(property "Reference" "C6548"
			(at 0 0 90)
			(layer "B.SilkS")
			(hide yes)
			(effects
				(font
					(size 1.27 1.27)
				)
				(justify mirror)
			)
		)
		(property "Value" ""
			(at 0 0 90)
			(layer "B.Fab")
			(effects
				(font
					(size 1.27 1.27)
				)
				(justify mirror)
			)
		)
		(duplicate_pad_numbers_are_jumpers no)
		(fp_line
			(start 0.299974 -0.150114)
			(end -0.299974 -0.150114)
			(stroke
				(width 0.1)
				(type default)
			)
			(layer "B.Fab")
		)
		(fp_line
			(start -0.299974 -0.150114)
			(end -0.299974 0.150114)
			(stroke
				(width 0.1)
				(type default)
			)
			(layer "B.Fab")
		)
		(fp_line
			(start 0.299974 0.150114)
			(end 0.299974 -0.150114)
			(stroke
				(width 0.1)
				(type default)
			)
			(layer "B.Fab")
		)
		(fp_line
			(start -0.299974 0.150114)
			(end 0.299974 0.150114)
			(stroke
				(width 0.1)
				(type default)
			)
			(layer "B.Fab")
		)
		(pad "1" smd rect
			(at 0.2667 0 270)
			(size 0.3048 0.381)
			(layers "B.Cu" "B.Mask" "B.Paste")
			(net "P5E_CPU0_P1_TX_BUF_C_DN<7>")
		)
		(pad "2" smd rect
			(at -0.2667 0 270)
			(size 0.3048 0.381)
			(layers "B.Cu" "B.Mask" "B.Paste")
			(net "P5E_CPU0_P1_TX_BUF_DN<7>")
		)
	)
	(footprint ""
		(layer "B.Cu")
		(at 180.271674 -194.885564 180)
		(property "Reference" "R775"
			(at 0 0 0)
			(layer "B.SilkS")
			(hide yes)
			(effects
				(font
					(size 1.27 1.27)
				)
				(justify mirror)
			)
		)
		(property "Value" ""
			(at 0 0 0)
			(layer "B.Fab")
			(effects
				(font
					(size 1.27 1.27)
				)
				(justify mirror)
			)
		)
		(duplicate_pad_numbers_are_jumpers no)
		(fp_line
			(start 0.7874 0.4064)
			(end 0.7874 -0.4064)
			(stroke
				(width 0.1524)
				(type default)
			)
			(layer "B.SilkS")
		)
		(fp_line
			(start 0.7874 -0.4064)
			(end -0.7874 -0.4064)
			(stroke
				(width 0.1524)
				(type default)
			)
			(layer "B.SilkS")
		)
		(fp_line
			(start -0.7874 0.4064)
			(end 0.7874 0.4064)
			(stroke
				(width 0.1524)
				(type default)
			)
			(layer "B.SilkS")
		)
		(fp_line
			(start -0.7874 -0.4064)
			(end -0.7874 0.4064)
			(stroke
				(width 0.1524)
				(type default)
			)
			(layer "B.SilkS")
		)
		(fp_line
			(start 0.67945 0.3048)
			(end 0.67945 -0.305054)
			(stroke
				(width 0.1)
				(type default)
			)
			(layer "B.Fab")
		)
		(fp_line
			(start 0.67945 -0.305054)
			(end 0.12065 -0.305054)
			(stroke
				(width 0.1)
				(type default)
			)
			(layer "B.Fab")
		)
		(fp_line
			(start 0.12065 0.3048)
			(end 0.67945 0.3048)
			(stroke
				(width 0.1)
				(type default)
			)
			(layer "B.Fab")
		)
		(fp_line
			(start 0.12065 0.2794)
			(end 0.12065 0.3048)
			(stroke
				(width 0.1)
				(type default)
			)
			(layer "B.Fab")
		)
		(fp_line
			(start 0.12065 -0.2794)
			(end -0.12065 -0.2794)
			(stroke
				(width 0.1)
				(type default)
			)
			(layer "B.Fab")
		)
		(fp_line
			(start 0.12065 -0.305054)
			(end 0.12065 -0.2794)
			(stroke
				(width 0.1)
				(type default)
			)
			(layer "B.Fab")
		)
		(fp_line
			(start -0.120396 0.3048)
			(end -0.120396 0.2794)
			(stroke
				(width 0.1)
				(type default)
			)
			(layer "B.Fab")
		)
		(fp_line
			(start -0.120396 0.2794)
			(end 0.12065 0.2794)
			(stroke
				(width 0.1)
				(type default)
			)
			(layer "B.Fab")
		)
		(fp_line
			(start -0.12065 -0.2794)
			(end -0.12065 -0.3048)
			(stroke
				(width 0.1)
				(type default)
			)
			(layer "B.Fab")
		)
		(fp_line
			(start -0.12065 -0.3048)
			(end -0.67945 -0.3048)
			(stroke
				(width 0.1)
				(type default)
			)
			(layer "B.Fab")
		)
		(fp_line
			(start -0.67945 0.3048)
			(end -0.120396 0.3048)
			(stroke
				(width 0.1)
				(type default)
			)
			(layer "B.Fab")
		)
		(fp_line
			(start -0.67945 -0.3048)
			(end -0.67945 0.3048)
			(stroke
				(width 0.1)
				(type default)
			)
			(layer "B.Fab")
		)
		(pad "1" smd circle
			(at 0.40005 0)
			(size 0 0)
			(layers "B.Cu" "B.Mask" "B.Paste")
			(net "PD_CHI_CPU1_DIMM_SAA")
		)
		(pad "2" smd circle
			(at -0.40005 0)
			(size 0 0)
			(layers "B.Cu" "B.Mask" "B.Paste")
			(net "GND")
		)
	)
	(footprint ""
		(layer "B.Cu")
		(at 417.406328 -395.148562 90)
		(property "Reference" "C792"
			(at 0 0 90)
			(layer "B.SilkS")
			(hide yes)
			(effects
				(font
					(size 1.27 1.27)
				)
				(justify mirror)
			)
		)
		(property "Value" ""
			(at 0 0 90)
			(layer "B.Fab")
			(effects
				(font
					(size 1.27 1.27)
				)
				(justify mirror)
			)
		)
		(duplicate_pad_numbers_are_jumpers no)
		(fp_line
			(start 0.299974 -0.150114)
			(end -0.299974 -0.150114)
			(stroke
				(width 0.1)
				(type default)
			)
			(layer "B.Fab")
		)
		(fp_line
			(start -0.299974 -0.150114)
			(end -0.299974 0.150114)
			(stroke
				(width 0.1)
				(type default)
			)
			(layer "B.Fab")
		)
		(fp_line
			(start 0.299974 0.150114)
			(end 0.299974 -0.150114)
			(stroke
				(width 0.1)
				(type default)
			)
			(layer "B.Fab")
		)
		(fp_line
			(start -0.299974 0.150114)
			(end 0.299974 0.150114)
			(stroke
				(width 0.1)
				(type default)
			)
			(layer "B.Fab")
		)
		(pad "1" smd rect
			(at 0.2667 0 270)
			(size 0.3048 0.381)
			(layers "B.Cu" "B.Mask" "B.Paste")
			(net "P0V9_CPU0_RT2_2A")
		)
		(pad "2" smd rect
			(at -0.2667 0 270)
			(size 0.3048 0.381)
			(layers "B.Cu" "B.Mask" "B.Paste")
			(net "GND")
		)
	)
)
